# SCM (Grand Teton) — schematic netlist excerpt (pin names and nets, part order shuffled) for the footprints in the layout excerpt that follows; sources: Cadence DE-HDL packaged netlist, KiCad conversion of 12092022_DA0F0TMDCD0_F0T_Management_Board_D_brd_V3_OCP.brd

R76  Q_RES  2K 1% CHIP  pkg 0402LF  page 11 : A = P3V3_AUX ; B = SGPIO_CLK_1
R103  Q_RES  4.7K 1% CHIP  pkg 0402LF  page 11 : A = P3V3_AUX ; B = RMII_TXEN

(kicad_pcb
	(version 20260206)
	(generator "pcbnew")
	(generator_version "10.0")
	(general
		(thickness 1.6)
		(legacy_teardrops no)
	)
	(paper "A4")
	(title_block
		(title "12092022_DA0F0TMDCD0_F0T_Management_Board_D_brd_V3_OCP.brd")
		(comment 1 "Grand Teton / footprints 347-348 of 1440")
	)
	(layers
		(0 "F.Cu" signal "TOP")
		(4 "In1.Cu" signal "GND")
		(6 "In2.Cu" signal "IN1")
		(8 "In3.Cu" signal "GND1")
		(10 "In4.Cu" signal "IN2")
		(12 "In5.Cu" signal "VCC")
		(14 "In6.Cu" signal "VCC1")
		(16 "In7.Cu" signal "IN3")
		(18 "In8.Cu" signal "GND2")
		(20 "In9.Cu" signal "IN4")
		(22 "In10.Cu" signal "GND3")
		(2 "B.Cu" signal "BOTTOM")
		(9 "F.Adhes" user "F.Adhesive")
		(11 "B.Adhes" user "B.Adhesive")
		(13 "F.Paste" user "Package Geometry/Pastemask Top")
		(15 "B.Paste" user "Package Geometry/Pastemask Bottom")
		(5 "F.SilkS" user "Ref Des/Silkscreen Top")
		(7 "B.SilkS" user "Ref Des/Silkscreen Bottom")
		(1 "F.Mask" user "Board Geometry/Soldermask Top")
		(3 "B.Mask" user "Board Geometry/Soldermask Bottom")
		(17 "Dwgs.User" user "User.Drawings")
		(19 "Cmts.User" user "User.Comments")
		(21 "Eco1.User" user "User.Eco1")
		(23 "Eco2.User" user "User.Eco2")
		(25 "Edge.Cuts" user "Board Geometry/Outline")
		(27 "Margin" user)
		(31 "F.CrtYd" user "Package Geometry/Place Bound Top")
		(29 "B.CrtYd" user "Package Geometry/Place Bound Bottom")
		(35 "F.Fab" user "Ref Des/Assembly Top")
		(33 "B.Fab" user "Ref Des/Assembly Bottom")
	)
	(footprint ""
		(layer "F.Cu")
		(at 38.6334 -109.8804)
		(property "Reference" "R76"
			(at 0 0 0)
			(layer "F.SilkS")
			(hide yes)
			(effects
				(font
					(size 1.27 1.27)
				)
			)
		)
		(property "Value" ""
			(at 0 0 0)
			(layer "F.Fab")
			(effects
				(font
					(size 1.27 1.27)
				)
			)
		)
		(duplicate_pad_numbers_are_jumpers no)
		(fp_line
			(start -0.7874 -0.4064)
			(end 0.7874 -0.4064)
			(stroke
				(width 0.1524)
				(type default)
			)
			(layer "F.SilkS")
		)
		(fp_line
			(start -0.7874 0.4064)
			(end -0.7874 -0.4064)
			(stroke
				(width 0.1524)
				(type default)
			)
			(layer "F.SilkS")
		)
		(fp_line
			(start 0.7874 -0.4064)
			(end 0.7874 0.4064)
			(stroke
				(width 0.1524)
				(type default)
			)
			(layer "F.SilkS")
		)
		(fp_line
			(start 0.7874 0.4064)
			(end -0.7874 0.4064)
			(stroke
				(width 0.1524)
				(type default)
			)
			(layer "F.SilkS")
		)
		(fp_line
			(start -0.67945 -0.305054)
			(end -0.12065 -0.305054)
			(stroke
				(width 0.1)
				(type default)
			)
			(layer "F.Fab")
		)
		(fp_line
			(start -0.67945 0.3048)
			(end -0.67945 -0.305054)
			(stroke
				(width 0.1)
				(type default)
			)
			(layer "F.Fab")
		)
		(fp_line
			(start -0.12065 -0.305054)
			(end -0.12065 -0.2794)
			(stroke
				(width 0.1)
				(type default)
			)
			(layer "F.Fab")
		)
		(fp_line
			(start -0.12065 -0.2794)
			(end 0.12065 -0.2794)
			(stroke
				(width 0.1)
				(type default)
			)
			(layer "F.Fab")
		)
		(fp_line
			(start -0.12065 0.2794)
			(end -0.12065 0.3048)
			(stroke
				(width 0.1)
				(type default)
			)
			(layer "F.Fab")
		)
		(fp_line
			(start -0.12065 0.3048)
			(end -0.67945 0.3048)
			(stroke
				(width 0.1)
				(type default)
			)
			(layer "F.Fab")
		)
		(fp_line
			(start 0.120396 0.2794)
			(end -0.12065 0.2794)
			(stroke
				(width 0.1)
				(type default)
			)
			(layer "F.Fab")
		)
		(fp_line
			(start 0.120396 0.3048)
			(end 0.120396 0.2794)
			(stroke
				(width 0.1)
				(type default)
			)
			(layer "F.Fab")
		)
		(fp_line
			(start 0.12065 -0.3048)
			(end 0.67945 -0.3048)
			(stroke
				(width 0.1)
				(type default)
			)
			(layer "F.Fab")
		)
		(fp_line
			(start 0.12065 -0.2794)
			(end 0.12065 -0.3048)
			(stroke
				(width 0.1)
				(type default)
			)
			(layer "F.Fab")
		)
		(fp_line
			(start 0.67945 -0.3048)
			(end 0.67945 0.3048)
			(stroke
				(width 0.1)
				(type default)
			)
			(layer "F.Fab")
		)
		(fp_line
			(start 0.67945 0.3048)
			(end 0.120396 0.3048)
			(stroke
				(width 0.1)
				(type default)
			)
			(layer "F.Fab")
		)
		(pad "1" smd circle
			(at -0.40005 0)
			(size 0 0)
			(layers "F.Cu" "F.Mask" "F.Paste")
			(net "P3V3_AUX")
		)
		(pad "2" smd circle
			(at 0.40005 0)
			(size 0 0)
			(layers "F.Cu" "F.Mask" "F.Paste")
			(net "SGPIO_CLK_1")
		)
	)
	(footprint ""
		(layer "F.Cu")
		(at 50.64887 -109.411008 90)
		(property "Reference" "R103"
			(at 0 0 90)
			(layer "F.SilkS")
			(hide yes)
			(effects
				(font
					(size 1.27 1.27)
				)
			)
		)
		(property "Value" ""
			(at 0 0 90)
			(layer "F.Fab")
			(effects
				(font
					(size 1.27 1.27)
				)
			)
		)
		(duplicate_pad_numbers_are_jumpers no)
		(fp_line
			(start 0.7874 -0.4064)
			(end 0.7874 0.4064)
			(stroke
				(width 0.1524)
				(type default)
			)
			(layer "F.SilkS")
		)
		(fp_line
			(start -0.7874 -0.4064)
			(end 0.7874 -0.4064)
			(stroke
				(width 0.1524)
				(type default)
			)
			(layer "F.SilkS")
		)
		(fp_line
			(start 0.7874 0.4064)
			(end -0.7874 0.4064)
			(stroke
				(width 0.1524)
				(type default)
			)
			(layer "F.SilkS")
		)
		(fp_line
			(start -0.7874 0.4064)
			(end -0.7874 -0.4064)
			(stroke
				(width 0.1524)
				(type default)
			)
			(layer "F.SilkS")
		)
		(fp_line
			(start -0.12065 -0.305054)
			(end -0.12065 -0.2794)
			(stroke
				(width 0.1)
				(type default)
			)
			(layer "F.Fab")
		)
		(fp_line
			(start -0.67945 -0.305054)
			(end -0.12065 -0.305054)
			(stroke
				(width 0.1)
				(type default)
			)
			(layer "F.Fab")
		)
		(fp_line
			(start 0.67945 -0.3048)
			(end 0.67945 0.3048)
			(stroke
				(width 0.1)
				(type default)
			)
			(layer "F.Fab")
		)
		(fp_line
			(start 0.12065 -0.3048)
			(end 0.67945 -0.3048)
			(stroke
				(width 0.1)
				(type default)
			)
			(layer "F.Fab")
		)
		(fp_line
			(start 0.12065 -0.2794)
			(end 0.12065 -0.3048)
			(stroke
				(width 0.1)
				(type default)
			)
			(layer "F.Fab")
		)
		(fp_line
			(start -0.12065 -0.2794)
			(end 0.12065 -0.2794)
			(stroke
				(width 0.1)
				(type default)
			)
			(layer "F.Fab")
		)
		(fp_line
			(start 0.120396 0.2794)
			(end -0.12065 0.2794)
			(stroke
				(width 0.1)
				(type default)
			)
			(layer "F.Fab")
		)
		(fp_line
			(start -0.12065 0.2794)
			(end -0.12065 0.3048)
			(stroke
				(width 0.1)
				(type default)
			)
			(layer "F.Fab")
		)
		(fp_line
			(start 0.67945 0.3048)
			(end 0.120396 0.3048)
			(stroke
				(width 0.1)
				(type default)
			)
			(layer "F.Fab")
		)
		(fp_line
			(start 0.120396 0.3048)
			(end 0.120396 0.2794)
			(stroke
				(width 0.1)
				(type default)
			)
			(layer "F.Fab")
		)
		(fp_line
			(start -0.12065 0.3048)
			(end -0.67945 0.3048)
			(stroke
				(width 0.1)
				(type default)
			)
			(layer "F.Fab")
		)
		(fp_line
			(start -0.67945 0.3048)
			(end -0.67945 -0.305054)
			(stroke
				(width 0.1)
				(type default)
			)
			(layer "F.Fab")
		)
		(pad "1" smd circle
			(at -0.40005 0 90)
			(size 0 0)
			(layers "F.Cu" "F.Mask" "F.Paste")
			(net "P3V3_AUX")
		)
		(pad "2" smd circle
			(at 0.40005 0 90)
			(size 0 0)
			(layers "F.Cu" "F.Mask" "F.Paste")
			(net "RMII_TXEN")
		)
	)
)
